# BASEBOARD_FAB2 (Tioga Pass) — schematic netlist excerpt (pin names and nets, part order shuffled) for the footprints in the layout excerpt that follows; sources: Cadence DE-HDL packaged netlist, KiCad conversion of Wiwynn_Tioga_Pass_MB.brd

J9M1  SCONN288_H44441003  SCONN  pkg PIP  page 84
  \12v\(1)  = P12V_NVDIMM_KLM
  VSS(93)  = GND
  DQ(4)  = M_K_DQ<4>
  VSS(92)  = GND
  DQ(0)  = M_K_DQ<0>
  VSS(91)  = GND
  DQS9P  = M_K_DQS_DP<9>
  DQS9N  = M_K_DQS_DN<9>
  VSS(90)  = GND
  DQ(6)  = M_K_DQ<6>
  VSS(89)  = GND
  DQ(2)  = M_K_DQ<2>
  VSS(88)  = GND
  DQ(12)  = M_K_DQ<12>
  VSS(87)  = GND
  DQ(8)  = M_K_DQ<8>
  VSS(86)  = GND
  DQS10P  = M_K_DQS_DP<10>
  DQS10N  = M_K_DQS_DN<10>
  VSS(85)  = GND
  DQ(14)  = M_K_DQ<14>
  VSS(84)  = GND
  DQ(10)  = M_K_DQ<10>
  VSS(83)  = GND
  DQ(20)  = M_K_DQ<20>
  VSS(82)  = GND
  DQ(16)  = M_K_DQ<16>
  VSS(81)  = GND
  DQS11P  = M_K_DQS_DP<11>
  DQS11N  = M_K_DQS_DN<11>
  VSS(80)  = GND
  DQ(22)  = M_K_DQ<22>
  VSS(79)  = GND
  DQ(18)  = M_K_DQ<18>
  VSS(78)  = GND
  DQ(28)  = M_K_DQ<28>
  VSS(77)  = GND
  DQ(24)  = M_K_DQ<24>
  VSS(76)  = GND
  DQS12P  = M_K_DQS_DP<12>
  DQS12N  = M_K_DQS_DN<12>
  VSS(75)  = GND
  DQ(30)  = M_K_DQ<30>
  VSS(74)  = GND
  DQ(26)  = M_K_DQ<26>
  VSS(73)  = GND
  CB(4)  = M_K_ECC<4>
  VSS(72)  = GND
  CB(0)  = M_K_ECC<0>
  VSS(71)  = GND
  DQS17P  = M_K_DQS_DP<17>
  DQS17N  = M_K_DQS_DN<17>
  VSS(70)  = GND
  CB(6)  = M_K_ECC<6>
  VSS(69)  = GND
  CB(2)  = M_K_ECC<2>
  VSS(68)  = GND
  RESET_N  = M_KLM_RST_N
  VDD(25)  = PVDDQ_KLM
  CKE(0)  = M_K_CKE<2>
  VDD(24)  = PVDDQ_KLM
  ACT_N  = M_K_ACT_N
  BG(0)  = M_K_BG<0>
  VDD(23)  = PVDDQ_KLM
  A12  = M_K_MA<12>
  A9  = M_K_MA<9>
  VDD(22)  = PVDDQ_KLM
  A8  = M_K_MA<8>
  A6  = M_K_MA<6>
  VDD(21)  = PVDDQ_KLM
  A3  = M_K_MA<3>
  A1  = M_K_MA<1>
  VDD(20)  = PVDDQ_KLM
  CK0P  = M_K_CLK_DP<2>
  CK0N  = M_K_CLK_DN<2>
  VDD(19)  = PVDDQ_KLM
  VTT(1)  = PVTT_KLM
  EVENT_N  = FM_DIMM_EVENT_COD_N
  A0  = M_K_MA<0>
  VDD(18)  = PVDDQ_KLM
  BA(0)  = M_K_BA<0>
  A16_RAS_N  = M_K_MA<16>
  VDD(17)  = PVDDQ_KLM
  S0_N  = M_K_CS_N<4>
  VDD(16)  = PVDDQ_KLM
  A15_CAS_N  = M_K_MA<15>
  ODT(0)  = M_K_ODT<2>
  VDD(15)  = PVDDQ_KLM
  S1_N  = M_K_CS_N<5>
  VDD(14)  = PVDDQ_KLM
  ODT(1)  = M_K_ODT<3>
  VDD(13)  = PVDDQ_KLM
  S2_N_C(0)  = M_K_CS_N<6>
  VSS(67)  = GND
  DQ(36)  = M_K_DQ<36>
  VSS(66)  = GND
  DQ(32)  = M_K_DQ<32>
  VSS(65)  = GND
  DQS13P  = M_K_DQS_DP<13>
  DQS13N  = M_K_DQS_DN<13>
  VSS(64)  = GND
  DQ(38)  = M_K_DQ<38>
  VSS(63)  = GND
  DQ(34)  = M_K_DQ<34>
  VSS(62)  = GND
  DQ(44)  = M_K_DQ<44>
  VSS(61)  = GND
  DQ(40)  = M_K_DQ<40>
  VSS(60)  = GND
  DQS14P  = M_K_DQS_DP<14>
  DQS14N  = M_K_DQS_DN<14>
  VSS(59)  = GND
  DQ(46)  = M_K_DQ<46>
  VSS(58)  = GND
  DQ(42)  = M_K_DQ<42>
  VSS(57)  = GND
  DQ(52)  = M_K_DQ<52>
  VSS(56)  = GND
  DQ(48)  = M_K_DQ<48>
  VSS(55)  = GND
  DQS15P  = M_K_DQS_DP<15>
  DQS15N  = M_K_DQS_DN<15>
  VSS(54)  = GND
  DQ(54)  = M_K_DQ<54>
  VSS(53)  = GND
  DQ(50)  = M_K_DQ<50>
  VSS(52)  = GND
  DQ(60)  = M_K_DQ<60>
  VSS(51)  = GND
  DQ(56)  = M_K_DQ<56>
  VSS(50)  = GND
  DQS16P  = M_K_DQS_DP<16>
  DQS16N  = M_K_DQS_DN<16>
  VSS(49)  = GND
  DQ(62)  = M_K_DQ<62>
  VSS(48)  = GND
  DQ(58)  = M_K_DQ<58>
  VSS(47)  = GND
  SA(0)  = PVPP_KLM
  SA(1)  = GND
  SCL  = SMB_DDR_KLM_VPP_SCL
  VPP(4)  = PVPP_KLM
  VPP(3)  = PVPP_KLM
  RFU(2)  = TP_CH_K_DIMM0_RFU_2
  \12v\(0)  = P12V_NVDIMM_KLM
  VREFCA  = M_K_VREF
  VSS(46)  = GND
  DQ(5)  = M_K_DQ<5>
  VSS(45)  = GND
  DQ(1)  = M_K_DQ<1>
  VSS(44)  = GND
  DQS0N  = M_K_DQS_DN<0>
  DQS0P  = M_K_DQS_DP<0>
  VSS(43)  = GND
  DQ(7)  = M_K_DQ<7>
  VSS(42)  = GND
  DQ(3)  = M_K_DQ<3>
  VSS(41)  = GND
  DQ(13)  = M_K_DQ<13>
  VSS(40)  = GND
  DQ(9)  = M_K_DQ<9>
  VSS(39)  = GND
  DQS1N  = M_K_DQS_DN<1>
  DQS1P  = M_K_DQS_DP<1>
  VSS(38)  = GND
  DQ(15)  = M_K_DQ<15>
  VSS(37)  = GND
  DQ(11)  = M_K_DQ<11>
  VSS(36)  = GND
  DQ(21)  = M_K_DQ<21>
  VSS(35)  = GND
  DQ(17)  = M_K_DQ<17>
  VSS(34)  = GND
  DQS2N  = M_K_DQS_DN<2>
  DQS2P  = M_K_DQS_DP<2>
  VSS(33)  = GND
  DQ(23)  = M_K_DQ<23>
  VSS(32)  = GND
  DQ(19)  = M_K_DQ<19>
  VSS(31)  = GND
  DQ(29)  = M_K_DQ<29>
  VSS(30)  = GND
  DQ(25)  = M_K_DQ<25>
  VSS(29)  = GND
  DQS3N  = M_K_DQS_DN<3>
  DQS3P  = M_K_DQS_DP<3>
  VSS(28)  = GND
  DQ(31)  = M_K_DQ<31>
  VSS(27)  = GND
  DQ(27)  = M_K_DQ<27>
  VSS(26)  = GND
  CB(5)  = M_K_ECC<5>
  VSS(25)  = GND
  CB(1)  = M_K_ECC<1>
  VSS(24)  = GND
  DQS8N  = M_K_DQS_DN<8>
  DQS8P  = M_K_DQS_DP<8>
  VSS(23)  = GND
  CB(7)  = M_K_ECC<7>
  VSS(22)  = GND
  CB(3)  = M_K_ECC<3>
  VSS(21)  = GND
  CKE(1)  = M_K_CKE<3>
  VDD(12)  = PVDDQ_KLM
  RFU(0)  = TP_CH_K_DIMM0_RFU_0
  VDD(11)  = PVDDQ_KLM
  BG(1)  = M_K_BG<1>
  ALERT_N  = M_K_ALERT_N
  VDD(10)  = PVDDQ_KLM
  A11  = M_K_MA<11>
  A7  = M_K_MA<7>
  VDD(9)  = PVDDQ_KLM
  A5  = M_K_MA<5>
  A4  = M_K_MA<4>
  VDD(8)  = PVDDQ_KLM
  A2  = M_K_MA<2>
  VDD(7)  = PVDDQ_KLM
  CK1P  = M_K_CLK_DP<3>
  CK1N  = M_K_CLK_DN<3>
  VDD(6)  = PVDDQ_KLM
  VTT(0)  = PVTT_KLM
  PAR  = M_K_PAR
  VDD(5)  = PVDDQ_KLM
  BA(1)  = M_K_BA<1>
  A10  = M_K_MA<10>
  VDD(4)  = PVDDQ_KLM
  RFU(1)  = TP_CH_K_DIMM0_RFU_1
  A14_WE_N  = M_K_MA<14>
  VDD(3)  = PVDDQ_KLM
  SAVE_N_NC  = FM_ADR_COMPLETE_KLM_N
  VDD(2)  = PVDDQ_KLM
  A13  = M_K_MA<13>
  VDD(1)  = PVDDQ_KLM
  A17  = M_K_MA<17>
  C(2)  = M_K_C<2>
  VDD(0)  = PVDDQ_KLM
  S3_N_C(1)  = M_K_CS_N<7>
  SA(2)  = GND
  VSS(20)  = GND
  DQ(37)  = M_K_DQ<37>
  VSS(19)  = GND
  DQ(33)  = M_K_DQ<33>
  VSS(18)  = GND
  DQS4N  = M_K_DQS_DN<4>
  DQS4P  = M_K_DQS_DP<4>
  VSS(17)  = GND
  DQ(39)  = M_K_DQ<39>
  VSS(16)  = GND
  DQ(35)  = M_K_DQ<35>
  VSS(15)  = GND
  DQ(45)  = M_K_DQ<45>
  VSS(14)  = GND
  DQ(41)  = M_K_DQ<41>
  VSS(13)  = GND
  DQS5N  = M_K_DQS_DN<5>
  DQS5P  = M_K_DQS_DP<5>
  VSS(12)  = GND
  DQ(47)  = M_K_DQ<47>
  VSS(11)  = GND
  DQ(43)  = M_K_DQ<43>
  VSS(10)  = GND
  DQ(53)  = M_K_DQ<53>
  VSS(9)  = GND
  DQ(49)  = M_K_DQ<49>
  VSS(8)  = GND
  DQS6N  = M_K_DQS_DN<6>
  DQS6P  = M_K_DQS_DP<6>
  VSS(7)  = GND
  DQ(55)  = M_K_DQ<55>
  VSS(6)  = GND
  DQ(51)  = M_K_DQ<51>
  VSS(5)  = GND
  DQ(61)  = M_K_DQ<61>
  VSS(4)  = GND
  DQ(57)  = M_K_DQ<57>
  VSS(3)  = GND
  DQS7N  = M_K_DQS_DN<7>
  DQS7P  = M_K_DQS_DP<7>
  VSS(2)  = GND
  DQ(63)  = M_K_DQ<63>
  VSS(1)  = GND
  DQ(59)  = M_K_DQ<59>
  VSS(0)  = GND
  VDDSPD  = PVPP_KLM
  SDA  = SMB_DDR_KLM_VPP_SDA
  VPP(1)  = PVPP_KLM
  VPP(0)  = PVPP_KLM
  VPP(2)  = PVPP_KLM

(kicad_pcb
	(version 20260206)
	(generator "pcbnew")
	(generator_version "10.0")
	(general
		(thickness 1.6)
		(legacy_teardrops no)
	)
	(paper "A4")
	(title_block
		(title "Wiwynn_Tioga_Pass_MB.brd")
		(comment 1 "Tioga Pass / footprint 2445 of 4770 (J9M1), pads 250-291 of 291")
	)
	(layers
		(0 "F.Cu" signal "TOP")
		(4 "In1.Cu" signal "L2GND")
		(6 "In2.Cu" signal "L3")
		(8 "In3.Cu" signal "L4GND")
		(10 "In4.Cu" signal "L5")
		(12 "In5.Cu" signal "L6GND")
		(14 "In6.Cu" signal "L7VCC")
		(16 "In7.Cu" signal "L8VCC")
		(18 "In8.Cu" signal "L9GND")
		(20 "In9.Cu" signal "L10")
		(22 "In10.Cu" signal "L11GND")
		(24 "In11.Cu" signal "L12")
		(26 "In12.Cu" signal "L13GND")
		(2 "B.Cu" signal "BOTTOM")
		(9 "F.Adhes" user "F.Adhesive")
		(11 "B.Adhes" user "B.Adhesive")
		(13 "F.Paste" user "Package Geometry/Pastemask Top")
		(15 "B.Paste" user "Package Geometry/Pastemask Bottom")
		(5 "F.SilkS" user "Ref Des/Silkscreen Top")
		(7 "B.SilkS" user "Ref Des/Silkscreen Bottom")
		(1 "F.Mask" user "Board Geometry/Soldermask Top")
		(3 "B.Mask" user "Board Geometry/Soldermask Bottom")
		(17 "Dwgs.User" user "User.Drawings")
		(19 "Cmts.User" user "User.Comments")
		(21 "Eco1.User" user "User.Eco1")
		(23 "Eco2.User" user "User.Eco2")
		(25 "Edge.Cuts" user "Board Geometry/Outline")
		(27 "Margin" user)
		(31 "F.CrtYd" user "Package Geometry/Place Bound Top")
		(29 "B.CrtYd" user "Package Geometry/Place Bound Bottom")
		(35 "F.Fab" user "Ref Des/Assembly Top")
		(33 "B.Fab" user "Ref Des/Assembly Bottom")
	)
	(footprint ""
		(layer "B.Cu")
		(at 29.699458 -132.876036 90)
		(property "Reference" "J9M1"
			(at 2.352548 37.991542 0)
			(unlocked yes)
			(layer "B.SilkS")
			(effects
				(font
					(size 0.7874 0.5842)
					(thickness 0.1524)
				)
				(justify left mirror)
			)
		)
		(property "Value" ""
			(at 0 0 90)
			(layer "B.Fab")
			(effects
				(font
					(size 1.27 1.27)
				)
				(justify mirror)
			)
		)
		(duplicate_pad_numbers_are_jumpers no)
		(pad "247" smd rect
			(at -4.59994 91.799918 270)
			(size 1.8034 0.508)
			(layers "B.Cu" "B.Mask" "B.Paste")
			(net "M_K_DQ<39>")
		)
		(pad "248" smd rect
			(at -4.59994 92.650056 270)
			(size 1.8034 0.508)
			(layers "B.Cu" "B.Mask" "B.Paste")
			(net "GND")
		)
		(pad "249" smd rect
			(at -4.59994 93.49994 270)
			(size 1.8034 0.508)
			(layers "B.Cu" "B.Mask" "B.Paste")
			(net "M_K_DQ<35>")
		)
		(pad "250" smd rect
			(at -4.59994 94.350078 270)
			(size 1.8034 0.508)
			(layers "B.Cu" "B.Mask" "B.Paste")
			(net "GND")
		)
		(pad "251" smd rect
			(at -4.59994 95.199962 270)
			(size 1.8034 0.508)
			(layers "B.Cu" "B.Mask" "B.Paste")
			(net "M_K_DQ<45>")
		)
		(pad "252" smd rect
			(at -4.59994 96.0501 270)
			(size 1.8034 0.508)
			(layers "B.Cu" "B.Mask" "B.Paste")
			(net "GND")
		)
		(pad "253" smd rect
			(at -4.59994 96.899984 270)
			(size 1.8034 0.508)
			(layers "B.Cu" "B.Mask" "B.Paste")
			(net "M_K_DQ<41>")
		)
		(pad "254" smd rect
			(at -4.59994 97.750122 270)
			(size 1.8034 0.508)
			(layers "B.Cu" "B.Mask" "B.Paste")
			(net "GND")
		)
		(pad "255" smd rect
			(at -4.59994 98.600006 270)
			(size 1.8034 0.508)
			(layers "B.Cu" "B.Mask" "B.Paste")
			(net "M_K_DQS_DN<5>")
		)
		(pad "256" smd rect
			(at -4.59994 99.44989 270)
			(size 1.8034 0.508)
			(layers "B.Cu" "B.Mask" "B.Paste")
			(net "M_K_DQS_DP<5>")
		)
		(pad "257" smd rect
			(at -4.59994 100.300028 270)
			(size 1.8034 0.508)
			(layers "B.Cu" "B.Mask" "B.Paste")
			(net "GND")
		)
		(pad "258" smd rect
			(at -4.59994 101.149912 270)
			(size 1.8034 0.508)
			(layers "B.Cu" "B.Mask" "B.Paste")
			(net "M_K_DQ<47>")
		)
		(pad "259" smd rect
			(at -4.59994 102.00005 270)
			(size 1.8034 0.508)
			(layers "B.Cu" "B.Mask" "B.Paste")
			(net "GND")
		)
		(pad "260" smd rect
			(at -4.59994 102.849934 270)
			(size 1.8034 0.508)
			(layers "B.Cu" "B.Mask" "B.Paste")
			(net "M_K_DQ<43>")
		)
		(pad "261" smd rect
			(at -4.59994 103.700072 270)
			(size 1.8034 0.508)
			(layers "B.Cu" "B.Mask" "B.Paste")
			(net "GND")
		)
		(pad "262" smd rect
			(at -4.59994 104.549956 270)
			(size 1.8034 0.508)
			(layers "B.Cu" "B.Mask" "B.Paste")
			(net "M_K_DQ<53>")
		)
		(pad "263" smd rect
			(at -4.59994 105.400094 270)
			(size 1.8034 0.508)
			(layers "B.Cu" "B.Mask" "B.Paste")
			(net "GND")
		)
		(pad "264" smd rect
			(at -4.59994 106.249978 270)
			(size 1.8034 0.508)
			(layers "B.Cu" "B.Mask" "B.Paste")
			(net "M_K_DQ<49>")
		)
		(pad "265" smd rect
			(at -4.59994 107.100116 270)
			(size 1.8034 0.508)
			(layers "B.Cu" "B.Mask" "B.Paste")
			(net "GND")
		)
		(pad "266" smd rect
			(at -4.59994 107.95 270)
			(size 1.8034 0.508)
			(layers "B.Cu" "B.Mask" "B.Paste")
			(net "M_K_DQS_DN<6>")
		)
		(pad "267" smd rect
			(at -4.59994 108.799884 270)
			(size 1.8034 0.508)
			(layers "B.Cu" "B.Mask" "B.Paste")
			(net "M_K_DQS_DP<6>")
		)
		(pad "268" smd rect
			(at -4.59994 109.650022 270)
			(size 1.8034 0.508)
			(layers "B.Cu" "B.Mask" "B.Paste")
			(net "GND")
		)
		(pad "269" smd rect
			(at -4.59994 110.499906 270)
			(size 1.8034 0.508)
			(layers "B.Cu" "B.Mask" "B.Paste")
			(net "M_K_DQ<55>")
		)
		(pad "270" smd rect
			(at -4.59994 111.350044 270)
			(size 1.8034 0.508)
			(layers "B.Cu" "B.Mask" "B.Paste")
			(net "GND")
		)
		(pad "271" smd rect
			(at -4.59994 112.199928 270)
			(size 1.8034 0.508)
			(layers "B.Cu" "B.Mask" "B.Paste")
			(net "M_K_DQ<51>")
		)
		(pad "272" smd rect
			(at -4.59994 113.050066 270)
			(size 1.8034 0.508)
			(layers "B.Cu" "B.Mask" "B.Paste")
			(net "GND")
		)
		(pad "273" smd rect
			(at -4.59994 113.89995 270)
			(size 1.8034 0.508)
			(layers "B.Cu" "B.Mask" "B.Paste")
			(net "M_K_DQ<61>")
		)
		(pad "274" smd rect
			(at -4.59994 114.750088 270)
			(size 1.8034 0.508)
			(layers "B.Cu" "B.Mask" "B.Paste")
			(net "GND")
		)
		(pad "275" smd rect
			(at -4.59994 115.599972 270)
			(size 1.8034 0.508)
			(layers "B.Cu" "B.Mask" "B.Paste")
			(net "M_K_DQ<57>")
		)
		(pad "276" smd rect
			(at -4.59994 116.45011 270)
			(size 1.8034 0.508)
			(layers "B.Cu" "B.Mask" "B.Paste")
			(net "GND")
		)
		(pad "277" smd rect
			(at -4.59994 117.299994 270)
			(size 1.8034 0.508)
			(layers "B.Cu" "B.Mask" "B.Paste")
			(net "M_K_DQS_DN<7>")
		)
		(pad "278" smd rect
			(at -4.59994 118.149878 270)
			(size 1.8034 0.508)
			(layers "B.Cu" "B.Mask" "B.Paste")
			(net "M_K_DQS_DP<7>")
		)
		(pad "279" smd rect
			(at -4.59994 119.000016 270)
			(size 1.8034 0.508)
			(layers "B.Cu" "B.Mask" "B.Paste")
			(net "GND")
		)
		(pad "280" smd rect
			(at -4.59994 119.8499 270)
			(size 1.8034 0.508)
			(layers "B.Cu" "B.Mask" "B.Paste")
			(net "M_K_DQ<63>")
		)
		(pad "281" smd rect
			(at -4.59994 120.700038 270)
			(size 1.8034 0.508)
			(layers "B.Cu" "B.Mask" "B.Paste")
			(net "GND")
		)
		(pad "282" smd rect
			(at -4.59994 121.549922 270)
			(size 1.8034 0.508)
			(layers "B.Cu" "B.Mask" "B.Paste")
			(net "M_K_DQ<59>")
		)
		(pad "283" smd rect
			(at -4.59994 122.40006 270)
			(size 1.8034 0.508)
			(layers "B.Cu" "B.Mask" "B.Paste")
			(net "GND")
		)
		(pad "284" smd rect
			(at -4.59994 123.249944 270)
			(size 1.8034 0.508)
			(layers "B.Cu" "B.Mask" "B.Paste")
			(net "PVPP_KLM")
		)
		(pad "285" smd rect
			(at -4.59994 124.100082 270)
			(size 1.8034 0.508)
			(layers "B.Cu" "B.Mask" "B.Paste")
			(net "SMB_DDR_KLM_VPP_SDA")
		)
		(pad "286" smd rect
			(at -4.59994 124.949966 270)
			(size 1.8034 0.508)
			(layers "B.Cu" "B.Mask" "B.Paste")
			(net "PVPP_KLM")
		)
		(pad "287" smd rect
			(at -4.59994 125.800104 270)
			(size 1.8034 0.508)
			(layers "B.Cu" "B.Mask" "B.Paste")
			(net "PVPP_KLM")
		)
		(pad "288" smd rect
			(at -4.59994 126.649988 270)
			(size 1.8034 0.508)
			(layers "B.Cu" "B.Mask" "B.Paste")
			(net "PVPP_KLM")
		)
	)
)
